(kicad_pcb
	(version 20260206)
	(generator "pcbnew")
	(generator_version "10.0")
	(general
		(thickness 1.6)
		(legacy_teardrops no)
	)
	(paper "A4")
	(title_block
		(title "panther-plus-userver — 13130-1b_20150205.brd")
		(comment 1 "Honey Badger (Wiwynn) / footprint 894 of 1509 (DIMM1), pads 23-29 of 210")
	)
	(layers
		(0 "F.Cu" signal "TOP")
		(4 "In1.Cu" signal "L2")
		(6 "In2.Cu" signal "L3")
		(8 "In3.Cu" signal "L4")
		(10 "In4.Cu" signal "L5")
		(12 "In5.Cu" signal "L6")
		(14 "In6.Cu" signal "L7")
		(16 "In7.Cu" signal "L8")
		(18 "In8.Cu" signal "L9")
		(20 "In9.Cu" signal "L10")
		(22 "In10.Cu" signal "L11")
		(2 "B.Cu" signal "BOTTOM")
		(9 "F.Adhes" user "F.Adhesive")
		(11 "B.Adhes" user "B.Adhesive")
		(13 "F.Paste" user "Package Geometry/Pastemask Top")
		(15 "B.Paste" user "Package Geometry/Pastemask Bottom")
		(5 "F.SilkS" user "Ref Des/Silkscreen Top")
		(7 "B.SilkS" user "Ref Des/Silkscreen Bottom")
		(1 "F.Mask" user "Board Geometry/Soldermask Top")
		(3 "B.Mask" user "Board Geometry/Soldermask Bottom")
		(17 "Dwgs.User" user "User.Drawings")
		(19 "Cmts.User" user "User.Comments")
		(21 "Eco1.User" user "User.Eco1")
		(23 "Eco2.User" user "User.Eco2")
		(25 "Edge.Cuts" user "Board Geometry/Outline")
		(27 "Margin" user)
		(31 "F.CrtYd" user "Package Geometry/Place Bound Top")
		(29 "B.CrtYd" user "Package Geometry/Place Bound Bottom")
		(35 "F.Fab" user "Ref Des/Assembly Top")
		(33 "B.Fab" user "Ref Des/Assembly Bottom")
	)
	(footprint ""
		(layer "B.Cu")
		(at 158.500064 -66.699892 180)
		(property "Reference" "DIMM1"
			(at 0 0 0)
			(layer "B.SilkS")
			(hide yes)
			(effects
				(font
					(size 1.27 1.27)
				)
				(justify mirror)
			)
		)
		(property "Value" "DDR3-204P-142-COLAY-1-GP-U"
			(at 41.312338 -16.676878 180)
			(unlocked yes)
			(layer "B.Fab")
			(hide yes)
			(effects
				(font
					(size 1.016 1.016)
					(thickness 0.1524)
				)
				(justify mirror)
			)
		)
		(property "Device Type" "AS0A626-J8R6-7H-COLAY-1"
			(at 41.312338 -18.200878 180)
			(unlocked yes)
			(layer "B.Fab")
			(hide yes)
			(effects
				(font
					(size 1.016 1.016)
					(thickness 0.1524)
				)
				(justify mirror)
			)
		)
		(duplicate_pad_numbers_are_jumpers no)
		(pad "21" smd custom
			(at -25.649936 -4.100068)
			(size 0.1143 0.1143)
			(layers "B.Cu" "B.Mask" "B.Paste")
			(net "M_A_DQ9")
			(options
				(clearance outline)
				(anchor circle)
			)
			(primitives
				(gr_poly
					(pts
						(xy 0 -0.9017) (xy -0.03175 -0.89916) (xy -0.0635 -0.889) (xy -0.09144 -0.87376) (xy -0.11684 -0.85344)
						(xy -0.13716 -0.82804) (xy -0.1524 -0.8001) (xy -0.16256 -0.76835) (xy -0.1651 -0.7366) (xy -0.1651 -0.44958)
						(xy -0.17272 -0.44196) (xy -0.19812 -0.4064) (xy -0.2032 -0.39624) (xy -0.20701 -0.38735) (xy -0.21209 -0.37719)
						(xy -0.2159 -0.36703) (xy -0.21844 -0.35687) (xy -0.22225 -0.34544) (xy -0.22352 -0.33528) (xy -0.22606 -0.32512)
						(xy -0.22733 -0.31369) (xy -0.22733 -0.30353) (xy -0.2286 -0.2921) (xy -0.22733 -0.28067) (xy -0.22733 -0.27051)
						(xy -0.22606 -0.25908) (xy -0.22352 -0.24892) (xy -0.22225 -0.23876) (xy -0.21844 -0.22733) (xy -0.2159 -0.21717)
						(xy -0.21209 -0.20701) (xy -0.20701 -0.19685) (xy -0.2032 -0.18796) (xy -0.19812 -0.1778) (xy -0.17272 -0.14224)
						(xy -0.1651 -0.13462) (xy -0.1651 0.7366) (xy -0.16256 0.76835) (xy -0.1524 0.8001) (xy -0.13716 0.82804)
						(xy -0.11684 0.85344) (xy -0.09144 0.87376) (xy -0.0635 0.889) (xy -0.03175 0.89916) (xy 0 0.9017)
						(xy 0.03175 0.89916) (xy 0.0635 0.889) (xy 0.09144 0.87376) (xy 0.11684 0.85344) (xy 0.13716 0.82804)
						(xy 0.1524 0.8001) (xy 0.16256 0.76835) (xy 0.1651 0.7366) (xy 0.1651 -0.13462) (xy 0.17272 -0.14224)
						(xy 0.19812 -0.1778) (xy 0.2032 -0.18796) (xy 0.20701 -0.19685) (xy 0.21209 -0.20701) (xy 0.2159 -0.21717)
						(xy 0.21844 -0.22733) (xy 0.22225 -0.23876) (xy 0.22352 -0.24892) (xy 0.22606 -0.25908) (xy 0.22733 -0.27051)
						(xy 0.22733 -0.28067) (xy 0.2286 -0.2921) (xy 0.22733 -0.30353) (xy 0.22733 -0.31369) (xy 0.22606 -0.32512)
						(xy 0.22352 -0.33528) (xy 0.22225 -0.34544) (xy 0.21844 -0.35687) (xy 0.2159 -0.36703) (xy 0.21209 -0.37719)
						(xy 0.20701 -0.38735) (xy 0.2032 -0.39624) (xy 0.19812 -0.4064) (xy 0.17272 -0.44196) (xy 0.1651 -0.44958)
						(xy 0.1651 -0.7366) (xy 0.16256 -0.76835) (xy 0.1524 -0.8001) (xy 0.13716 -0.82804) (xy 0.11684 -0.85344)
						(xy 0.09144 -0.87376) (xy 0.0635 -0.889) (xy 0.03175 -0.89916)
					)
					(width 0)
					(fill yes)
				)
			)
		)
		(pad "22" smd custom
			(at -25.349962 4.100068)
			(size 0.1143 0.1143)
			(layers "B.Cu" "B.Mask" "B.Paste")
			(net "M_A_DQ12")
			(options
				(clearance outline)
				(anchor circle)
			)
			(primitives
				(gr_poly
					(pts
						(xy 0 -0.9017) (xy -0.03175 -0.89916) (xy -0.0635 -0.889) (xy -0.09144 -0.87376) (xy -0.11684 -0.85344)
						(xy -0.13716 -0.82804) (xy -0.1524 -0.8001) (xy -0.16256 -0.76835) (xy -0.1651 -0.7366) (xy -0.1651 0.13462)
						(xy -0.17272 0.14224) (xy -0.19812 0.1778) (xy -0.2032 0.18796) (xy -0.20701 0.19685) (xy -0.21209 0.20701)
						(xy -0.2159 0.21717) (xy -0.21844 0.22733) (xy -0.22225 0.23876) (xy -0.22352 0.24892) (xy -0.22606 0.25908)
						(xy -0.22733 0.27051) (xy -0.22733 0.28067) (xy -0.2286 0.2921) (xy -0.22733 0.30353) (xy -0.22733 0.31369)
						(xy -0.22606 0.32512) (xy -0.22352 0.33528) (xy -0.22225 0.34544) (xy -0.21844 0.35687) (xy -0.2159 0.36703)
						(xy -0.21209 0.37719) (xy -0.20701 0.38735) (xy -0.2032 0.39624) (xy -0.19812 0.4064) (xy -0.17272 0.44196)
						(xy -0.1651 0.44958) (xy -0.1651 0.7366) (xy -0.16256 0.76835) (xy -0.1524 0.8001) (xy -0.13716 0.82804)
						(xy -0.11684 0.85344) (xy -0.09144 0.87376) (xy -0.0635 0.889) (xy -0.03175 0.89916) (xy 0 0.9017)
						(xy 0.03175 0.89916) (xy 0.0635 0.889) (xy 0.09144 0.87376) (xy 0.11684 0.85344) (xy 0.13716 0.82804)
						(xy 0.1524 0.8001) (xy 0.16256 0.76835) (xy 0.1651 0.7366) (xy 0.1651 0.44958) (xy 0.17272 0.44196)
						(xy 0.19812 0.4064) (xy 0.2032 0.39624) (xy 0.20701 0.38735) (xy 0.21209 0.37719) (xy 0.2159 0.36703)
						(xy 0.21844 0.35687) (xy 0.22225 0.34544) (xy 0.22352 0.33528) (xy 0.22606 0.32512) (xy 0.22733 0.31369)
						(xy 0.22733 0.30353) (xy 0.2286 0.2921) (xy 0.22733 0.28067) (xy 0.22733 0.27051) (xy 0.22606 0.25908)
						(xy 0.22352 0.24892) (xy 0.22225 0.23876) (xy 0.21844 0.22733) (xy 0.2159 0.21717) (xy 0.21209 0.20701)
						(xy 0.20701 0.19685) (xy 0.2032 0.18796) (xy 0.19812 0.1778) (xy 0.17272 0.14224) (xy 0.1651 0.13462)
						(xy 0.1651 -0.7366) (xy 0.16256 -0.76835) (xy 0.1524 -0.8001) (xy 0.13716 -0.82804) (xy 0.11684 -0.85344)
						(xy 0.09144 -0.87376) (xy 0.0635 -0.889) (xy 0.03175 -0.89916)
					)
					(width 0)
					(fill yes)
				)
			)
		)
		(pad "23" smd custom
			(at -25.049988 -4.100068)
			(size 0.1143 0.1143)
			(layers "B.Cu" "B.Mask" "B.Paste")
			(net "GND")
			(options
				(clearance outline)
				(anchor circle)
			)
			(primitives
				(gr_poly
					(pts
						(xy 0 -0.9017) (xy -0.03175 -0.89916) (xy -0.0635 -0.889) (xy -0.09144 -0.87376) (xy -0.11684 -0.85344)
						(xy -0.13716 -0.82804) (xy -0.1524 -0.8001) (xy -0.16256 -0.76835) (xy -0.1651 -0.7366) (xy -0.1651 -0.19685)
						(xy -0.17272 -0.18923) (xy -0.17907 -0.18034) (xy -0.18669 -0.17145) (xy -0.19177 -0.16256) (xy -0.19812 -0.15367)
						(xy -0.20828 -0.13335) (xy -0.21971 -0.10287) (xy -0.22225 -0.09271) (xy -0.22479 -0.08128) (xy -0.22606 -0.07112)
						(xy -0.2286 -0.05969) (xy -0.2286 -0.01651) (xy -0.22606 -0.00508) (xy -0.22479 0.00508) (xy -0.22225 0.01651)
						(xy -0.21971 0.02667) (xy -0.20828 0.05715) (xy -0.19812 0.07747) (xy -0.19177 0.08636) (xy -0.18669 0.09525)
						(xy -0.17907 0.10414) (xy -0.17272 0.11303) (xy -0.1651 0.12065) (xy -0.1651 0.7366) (xy -0.16256 0.76835)
						(xy -0.1524 0.8001) (xy -0.13716 0.82804) (xy -0.11684 0.85344) (xy -0.09144 0.87376) (xy -0.0635 0.889)
						(xy -0.03175 0.89916) (xy 0 0.9017) (xy 0.03175 0.89916) (xy 0.0635 0.889) (xy 0.09144 0.87376)
						(xy 0.11684 0.85344) (xy 0.13716 0.82804) (xy 0.1524 0.8001) (xy 0.16256 0.76835) (xy 0.1651 0.7366)
						(xy 0.1651 0.11938) (xy 0.17272 0.11176) (xy 0.19812 0.0762) (xy 0.2032 0.06604) (xy 0.20701 0.05715)
						(xy 0.21209 0.04699) (xy 0.2159 0.03683) (xy 0.21844 0.02667) (xy 0.22225 0.01524) (xy 0.22352 0.00508)
						(xy 0.22606 -0.00508) (xy 0.22733 -0.01651) (xy 0.22733 -0.02667) (xy 0.2286 -0.0381) (xy 0.22733 -0.04953)
						(xy 0.22733 -0.05969) (xy 0.22606 -0.07112) (xy 0.22352 -0.08128) (xy 0.22225 -0.09144) (xy 0.21844 -0.10287)
						(xy 0.2159 -0.11303) (xy 0.21209 -0.12319) (xy 0.20701 -0.13335) (xy 0.2032 -0.14224) (xy 0.19812 -0.1524)
						(xy 0.17272 -0.18796) (xy 0.1651 -0.19558) (xy 0.1651 -0.7366) (xy 0.16256 -0.76835) (xy 0.1524 -0.8001)
						(xy 0.13716 -0.82804) (xy 0.11684 -0.85344) (xy 0.09144 -0.87376) (xy 0.0635 -0.889) (xy 0.03175 -0.89916)
					)
					(width 0)
					(fill yes)
				)
			)
		)
		(pad "24" smd custom
			(at -24.750014 4.100068)
			(size 0.1143 0.1143)
			(layers "B.Cu" "B.Mask" "B.Paste")
			(net "M_A_DQ13")
			(options
				(clearance outline)
				(anchor circle)
			)
			(primitives
				(gr_poly
					(pts
						(xy 0 -0.9017) (xy -0.03175 -0.89916) (xy -0.0635 -0.889) (xy -0.09144 -0.87376) (xy -0.11684 -0.85344)
						(xy -0.13716 -0.82804) (xy -0.1524 -0.8001) (xy -0.16256 -0.76835) (xy -0.1651 -0.7366) (xy -0.1651 -0.11938)
						(xy -0.17272 -0.11176) (xy -0.19812 -0.0762) (xy -0.2032 -0.06604) (xy -0.20701 -0.05715) (xy -0.21209 -0.04699)
						(xy -0.2159 -0.03683) (xy -0.21844 -0.02667) (xy -0.22225 -0.01524) (xy -0.22352 -0.00508) (xy -0.22606 0.00508)
						(xy -0.22733 0.01651) (xy -0.22733 0.02667) (xy -0.2286 0.0381) (xy -0.22733 0.04953) (xy -0.22733 0.05969)
						(xy -0.22606 0.07112) (xy -0.22352 0.08128) (xy -0.22225 0.09144) (xy -0.21844 0.10287) (xy -0.2159 0.11303)
						(xy -0.21209 0.12319) (xy -0.20701 0.13335) (xy -0.2032 0.14224) (xy -0.19812 0.1524) (xy -0.17272 0.18796)
						(xy -0.1651 0.19558) (xy -0.1651 0.7366) (xy -0.16256 0.76835) (xy -0.1524 0.8001) (xy -0.13716 0.82804)
						(xy -0.11684 0.85344) (xy -0.09144 0.87376) (xy -0.0635 0.889) (xy -0.03175 0.89916) (xy 0 0.9017)
						(xy 0.03175 0.89916) (xy 0.0635 0.889) (xy 0.09144 0.87376) (xy 0.11684 0.85344) (xy 0.13716 0.82804)
						(xy 0.1524 0.8001) (xy 0.16256 0.76835) (xy 0.1651 0.7366) (xy 0.1651 0.19685) (xy 0.17272 0.18923)
						(xy 0.17907 0.18034) (xy 0.18669 0.17145) (xy 0.19177 0.16256) (xy 0.19812 0.15367) (xy 0.20828 0.13335)
						(xy 0.21971 0.10287) (xy 0.22225 0.09271) (xy 0.22479 0.08128) (xy 0.22606 0.07112) (xy 0.2286 0.05969)
						(xy 0.2286 0.01651) (xy 0.22606 0.00508) (xy 0.22479 -0.00508) (xy 0.22225 -0.01651) (xy 0.21971 -0.02667)
						(xy 0.20828 -0.05715) (xy 0.19812 -0.07747) (xy 0.19177 -0.08636) (xy 0.18669 -0.09525) (xy 0.17907 -0.10414)
						(xy 0.17272 -0.11303) (xy 0.1651 -0.12065) (xy 0.1651 -0.7366) (xy 0.16256 -0.76835) (xy 0.1524 -0.8001)
						(xy 0.13716 -0.82804) (xy 0.11684 -0.85344) (xy 0.09144 -0.87376) (xy 0.0635 -0.889) (xy 0.03175 -0.89916)
					)
					(width 0)
					(fill yes)
				)
			)
		)
		(pad "25" smd custom
			(at -24.45004 -4.100068)
			(size 0.1143 0.1143)
			(layers "B.Cu" "B.Mask" "B.Paste")
			(net "M_A_DQS_DN1")
			(options
				(clearance outline)
				(anchor circle)
			)
			(primitives
				(gr_poly
					(pts
						(xy 0 -0.9017) (xy -0.03175 -0.89916) (xy -0.0635 -0.889) (xy -0.09144 -0.87376) (xy -0.11684 -0.85344)
						(xy -0.13716 -0.82804) (xy -0.1524 -0.8001) (xy -0.16256 -0.76835) (xy -0.1651 -0.7366) (xy -0.1651 -0.44958)
						(xy -0.17272 -0.44196) (xy -0.19812 -0.4064) (xy -0.2032 -0.39624) (xy -0.20701 -0.38735) (xy -0.21209 -0.37719)
						(xy -0.2159 -0.36703) (xy -0.21844 -0.35687) (xy -0.22225 -0.34544) (xy -0.22352 -0.33528) (xy -0.22606 -0.32512)
						(xy -0.22733 -0.31369) (xy -0.22733 -0.30353) (xy -0.2286 -0.2921) (xy -0.22733 -0.28067) (xy -0.22733 -0.27051)
						(xy -0.22606 -0.25908) (xy -0.22352 -0.24892) (xy -0.22225 -0.23876) (xy -0.21844 -0.22733) (xy -0.2159 -0.21717)
						(xy -0.21209 -0.20701) (xy -0.20701 -0.19685) (xy -0.2032 -0.18796) (xy -0.19812 -0.1778) (xy -0.17272 -0.14224)
						(xy -0.1651 -0.13462) (xy -0.1651 0.7366) (xy -0.16256 0.76835) (xy -0.1524 0.8001) (xy -0.13716 0.82804)
						(xy -0.11684 0.85344) (xy -0.09144 0.87376) (xy -0.0635 0.889) (xy -0.03175 0.89916) (xy 0 0.9017)
						(xy 0.03175 0.89916) (xy 0.0635 0.889) (xy 0.09144 0.87376) (xy 0.11684 0.85344) (xy 0.13716 0.82804)
						(xy 0.1524 0.8001) (xy 0.16256 0.76835) (xy 0.1651 0.7366) (xy 0.1651 -0.13462) (xy 0.17272 -0.14224)
						(xy 0.19812 -0.1778) (xy 0.2032 -0.18796) (xy 0.20701 -0.19685) (xy 0.21209 -0.20701) (xy 0.2159 -0.21717)
						(xy 0.21844 -0.22733) (xy 0.22225 -0.23876) (xy 0.22352 -0.24892) (xy 0.22606 -0.25908) (xy 0.22733 -0.27051)
						(xy 0.22733 -0.28067) (xy 0.2286 -0.2921) (xy 0.22733 -0.30353) (xy 0.22733 -0.31369) (xy 0.22606 -0.32512)
						(xy 0.22352 -0.33528) (xy 0.22225 -0.34544) (xy 0.21844 -0.35687) (xy 0.2159 -0.36703) (xy 0.21209 -0.37719)
						(xy 0.20701 -0.38735) (xy 0.2032 -0.39624) (xy 0.19812 -0.4064) (xy 0.17272 -0.44196) (xy 0.1651 -0.44958)
						(xy 0.1651 -0.7366) (xy 0.16256 -0.76835) (xy 0.1524 -0.8001) (xy 0.13716 -0.82804) (xy 0.11684 -0.85344)
						(xy 0.09144 -0.87376) (xy 0.0635 -0.889) (xy 0.03175 -0.89916)
					)
					(width 0)
					(fill yes)
				)
			)
		)
		(pad "26" smd custom
			(at -24.150066 4.100068)
			(size 0.1143 0.1143)
			(layers "B.Cu" "B.Mask" "B.Paste")
			(net "GND")
			(options
				(clearance outline)
				(anchor circle)
			)
			(primitives
				(gr_poly
					(pts
						(xy 0 -0.9017) (xy -0.03175 -0.89916) (xy -0.0635 -0.889) (xy -0.09144 -0.87376) (xy -0.11684 -0.85344)
						(xy -0.13716 -0.82804) (xy -0.1524 -0.8001) (xy -0.16256 -0.76835) (xy -0.1651 -0.7366) (xy -0.1651 0.13462)
						(xy -0.17272 0.14224) (xy -0.19812 0.1778) (xy -0.2032 0.18796) (xy -0.20701 0.19685) (xy -0.21209 0.20701)
						(xy -0.2159 0.21717) (xy -0.21844 0.22733) (xy -0.22225 0.23876) (xy -0.22352 0.24892) (xy -0.22606 0.25908)
						(xy -0.22733 0.27051) (xy -0.22733 0.28067) (xy -0.2286 0.2921) (xy -0.22733 0.30353) (xy -0.22733 0.31369)
						(xy -0.22606 0.32512) (xy -0.22352 0.33528) (xy -0.22225 0.34544) (xy -0.21844 0.35687) (xy -0.2159 0.36703)
						(xy -0.21209 0.37719) (xy -0.20701 0.38735) (xy -0.2032 0.39624) (xy -0.19812 0.4064) (xy -0.17272 0.44196)
						(xy -0.1651 0.44958) (xy -0.1651 0.7366) (xy -0.16256 0.76835) (xy -0.1524 0.8001) (xy -0.13716 0.82804)
						(xy -0.11684 0.85344) (xy -0.09144 0.87376) (xy -0.0635 0.889) (xy -0.03175 0.89916) (xy 0 0.9017)
						(xy 0.03175 0.89916) (xy 0.0635 0.889) (xy 0.09144 0.87376) (xy 0.11684 0.85344) (xy 0.13716 0.82804)
						(xy 0.1524 0.8001) (xy 0.16256 0.76835) (xy 0.1651 0.7366) (xy 0.1651 0.44958) (xy 0.17272 0.44196)
						(xy 0.19812 0.4064) (xy 0.2032 0.39624) (xy 0.20701 0.38735) (xy 0.21209 0.37719) (xy 0.2159 0.36703)
						(xy 0.21844 0.35687) (xy 0.22225 0.34544) (xy 0.22352 0.33528) (xy 0.22606 0.32512) (xy 0.22733 0.31369)
						(xy 0.22733 0.30353) (xy 0.2286 0.2921) (xy 0.22733 0.28067) (xy 0.22733 0.27051) (xy 0.22606 0.25908)
						(xy 0.22352 0.24892) (xy 0.22225 0.23876) (xy 0.21844 0.22733) (xy 0.2159 0.21717) (xy 0.21209 0.20701)
						(xy 0.20701 0.19685) (xy 0.2032 0.18796) (xy 0.19812 0.1778) (xy 0.17272 0.14224) (xy 0.1651 0.13462)
						(xy 0.1651 -0.7366) (xy 0.16256 -0.76835) (xy 0.1524 -0.8001) (xy 0.13716 -0.82804) (xy 0.11684 -0.85344)
						(xy 0.09144 -0.87376) (xy 0.0635 -0.889) (xy 0.03175 -0.89916)
					)
					(width 0)
					(fill yes)
				)
			)
		)
		(pad "27" smd custom
			(at -23.850092 -4.100068)
			(size 0.1143 0.1143)
			(layers "B.Cu" "B.Mask" "B.Paste")
			(net "M_A_DQS_DP1")
			(options
				(clearance outline)
				(anchor circle)
			)
			(primitives
				(gr_poly
					(pts
						(xy 0 -0.9017) (xy -0.03175 -0.89916) (xy -0.0635 -0.889) (xy -0.09144 -0.87376) (xy -0.11684 -0.85344)
						(xy -0.13716 -0.82804) (xy -0.1524 -0.8001) (xy -0.16256 -0.76835) (xy -0.1651 -0.7366) (xy -0.1651 -0.19685)
						(xy -0.17272 -0.18923) (xy -0.17907 -0.18034) (xy -0.18669 -0.17145) (xy -0.19177 -0.16256) (xy -0.19812 -0.15367)
						(xy -0.20828 -0.13335) (xy -0.21971 -0.10287) (xy -0.22225 -0.09271) (xy -0.22479 -0.08128) (xy -0.22606 -0.07112)
						(xy -0.2286 -0.05969) (xy -0.2286 -0.01651) (xy -0.22606 -0.00508) (xy -0.22479 0.00508) (xy -0.22225 0.01651)
						(xy -0.21971 0.02667) (xy -0.20828 0.05715) (xy -0.19812 0.07747) (xy -0.19177 0.08636) (xy -0.18669 0.09525)
						(xy -0.17907 0.10414) (xy -0.17272 0.11303) (xy -0.1651 0.12065) (xy -0.1651 0.7366) (xy -0.16256 0.76835)
						(xy -0.1524 0.8001) (xy -0.13716 0.82804) (xy -0.11684 0.85344) (xy -0.09144 0.87376) (xy -0.0635 0.889)
						(xy -0.03175 0.89916) (xy 0 0.9017) (xy 0.03175 0.89916) (xy 0.0635 0.889) (xy 0.09144 0.87376)
						(xy 0.11684 0.85344) (xy 0.13716 0.82804) (xy 0.1524 0.8001) (xy 0.16256 0.76835) (xy 0.1651 0.7366)
						(xy 0.1651 0.11938) (xy 0.17272 0.11176) (xy 0.19812 0.0762) (xy 0.2032 0.06604) (xy 0.20701 0.05715)
						(xy 0.21209 0.04699) (xy 0.2159 0.03683) (xy 0.21844 0.02667) (xy 0.22225 0.01524) (xy 0.22352 0.00508)
						(xy 0.22606 -0.00508) (xy 0.22733 -0.01651) (xy 0.22733 -0.02667) (xy 0.2286 -0.0381) (xy 0.22733 -0.04953)
						(xy 0.22733 -0.05969) (xy 0.22606 -0.07112) (xy 0.22352 -0.08128) (xy 0.22225 -0.09144) (xy 0.21844 -0.10287)
						(xy 0.2159 -0.11303) (xy 0.21209 -0.12319) (xy 0.20701 -0.13335) (xy 0.2032 -0.14224) (xy 0.19812 -0.1524)
						(xy 0.17272 -0.18796) (xy 0.1651 -0.19558) (xy 0.1651 -0.7366) (xy 0.16256 -0.76835) (xy 0.1524 -0.8001)
						(xy 0.13716 -0.82804) (xy 0.11684 -0.85344) (xy 0.09144 -0.87376) (xy 0.0635 -0.889) (xy 0.03175 -0.89916)
					)
					(width 0)
					(fill yes)
				)
			)
		)
	)
)
